# BASEBOARD_FAB2 (Tioga Pass) — schematic netlist excerpt (pin names and nets, part order shuffled) for the footprints in the layout excerpt that follows; sources: Cadence DE-HDL packaged netlist, KiCad conversion of Wiwynn_Tioga_Pass_MB.brd

J9L1  SCONN288_H44441003  SCONN  pkg PIP  page 88
  \12v\(1)  = P12V_NVDIMM_KLM
  VSS(93)  = GND
  DQ(4)  = M_M_DQ<4>
  VSS(92)  = GND
  DQ(0)  = M_M_DQ<0>
  VSS(91)  = GND
  DQS9P  = M_M_DQS_DP<9>
  DQS9N  = M_M_DQS_DN<9>
  VSS(90)  = GND
  DQ(6)  = M_M_DQ<6>
  VSS(89)  = GND
  DQ(2)  = M_M_DQ<2>
  VSS(88)  = GND
  DQ(12)  = M_M_DQ<12>
  VSS(87)  = GND
  DQ(8)  = M_M_DQ<8>
  VSS(86)  = GND
  DQS10P  = M_M_DQS_DP<10>
  DQS10N  = M_M_DQS_DN<10>
  VSS(85)  = GND
  DQ(14)  = M_M_DQ<14>
  VSS(84)  = GND
  DQ(10)  = M_M_DQ<10>
  VSS(83)  = GND
  DQ(20)  = M_M_DQ<20>
  VSS(82)  = GND
  DQ(16)  = M_M_DQ<16>
  VSS(81)  = GND
  DQS11P  = M_M_DQS_DP<11>
  DQS11N  = M_M_DQS_DN<11>
  VSS(80)  = GND
  DQ(22)  = M_M_DQ<22>
  VSS(79)  = GND
  DQ(18)  = M_M_DQ<18>
  VSS(78)  = GND
  DQ(28)  = M_M_DQ<28>
  VSS(77)  = GND
  DQ(24)  = M_M_DQ<24>
  VSS(76)  = GND
  DQS12P  = M_M_DQS_DP<12>
  DQS12N  = M_M_DQS_DN<12>
  VSS(75)  = GND
  DQ(30)  = M_M_DQ<30>
  VSS(74)  = GND
  DQ(26)  = M_M_DQ<26>
  VSS(73)  = GND
  CB(4)  = M_M_ECC<4>
  VSS(72)  = GND
  CB(0)  = M_M_ECC<0>
  VSS(71)  = GND
  DQS17P  = M_M_DQS_DP<17>
  DQS17N  = M_M_DQS_DN<17>
  VSS(70)  = GND
  CB(6)  = M_M_ECC<6>
  VSS(69)  = GND
  CB(2)  = M_M_ECC<2>
  VSS(68)  = GND
  RESET_N  = M_KLM_RST_N
  VDD(25)  = PVDDQ_KLM
  CKE(0)  = M_M_CKE<2>
  VDD(24)  = PVDDQ_KLM
  ACT_N  = M_M_ACT_N
  BG(0)  = M_M_BG<0>
  VDD(23)  = PVDDQ_KLM
  A12  = M_M_MA<12>
  A9  = M_M_MA<9>
  VDD(22)  = PVDDQ_KLM
  A8  = M_M_MA<8>
  A6  = M_M_MA<6>
  VDD(21)  = PVDDQ_KLM
  A3  = M_M_MA<3>
  A1  = M_M_MA<1>
  VDD(20)  = PVDDQ_KLM
  CK0P  = M_M_CLK_DP<2>
  CK0N  = M_M_CLK_DN<2>
  VDD(19)  = PVDDQ_KLM
  VTT(1)  = PVTT_KLM
  EVENT_N  = FM_DIMM_EVENT_COD_N
  A0  = M_M_MA<0>
  VDD(18)  = PVDDQ_KLM
  BA(0)  = M_M_BA<0>
  A16_RAS_N  = M_M_MA<16>
  VDD(17)  = PVDDQ_KLM
  S0_N  = M_M_CS_N<4>
  VDD(16)  = PVDDQ_KLM
  A15_CAS_N  = M_M_MA<15>
  ODT(0)  = M_M_ODT<2>
  VDD(15)  = PVDDQ_KLM
  S1_N  = M_M_CS_N<5>
  VDD(14)  = PVDDQ_KLM
  ODT(1)  = M_M_ODT<3>
  VDD(13)  = PVDDQ_KLM
  S2_N_C(0)  = M_M_CS_N<6>
  VSS(67)  = GND
  DQ(36)  = M_M_DQ<36>
  VSS(66)  = GND
  DQ(32)  = M_M_DQ<32>
  VSS(65)  = GND
  DQS13P  = M_M_DQS_DP<13>
  DQS13N  = M_M_DQS_DN<13>
  VSS(64)  = GND
  DQ(38)  = M_M_DQ<38>
  VSS(63)  = GND
  DQ(34)  = M_M_DQ<34>
  VSS(62)  = GND
  DQ(44)  = M_M_DQ<44>
  VSS(61)  = GND
  DQ(40)  = M_M_DQ<40>
  VSS(60)  = GND
  DQS14P  = M_M_DQS_DP<14>
  DQS14N  = M_M_DQS_DN<14>
  VSS(59)  = GND
  DQ(46)  = M_M_DQ<46>
  VSS(58)  = GND
  DQ(42)  = M_M_DQ<42>
  VSS(57)  = GND
  DQ(52)  = M_M_DQ<52>
  VSS(56)  = GND
  DQ(48)  = M_M_DQ<48>
  VSS(55)  = GND
  DQS15P  = M_M_DQS_DP<15>
  DQS15N  = M_M_DQS_DN<15>
  VSS(54)  = GND
  DQ(54)  = M_M_DQ<54>
  VSS(53)  = GND
  DQ(50)  = M_M_DQ<50>
  VSS(52)  = GND
  DQ(60)  = M_M_DQ<60>
  VSS(51)  = GND
  DQ(56)  = M_M_DQ<56>
  VSS(50)  = GND
  DQS16P  = M_M_DQS_DP<16>
  DQS16N  = M_M_DQS_DN<16>
  VSS(49)  = GND
  DQ(62)  = M_M_DQ<62>
  VSS(48)  = GND
  DQ(58)  = M_M_DQ<58>
  VSS(47)  = GND
  SA(0)  = PVPP_KLM
  SA(1)  = GND
  SCL  = SMB_DDR_KLM_VPP_SCL
  VPP(4)  = PVPP_KLM
  VPP(3)  = PVPP_KLM
  RFU(2)  = TP_CH_M_DIMM_M1_RFU_2
  \12v\(0)  = P12V_NVDIMM_KLM
  VREFCA  = M_M_VREF
  VSS(46)  = GND
  DQ(5)  = M_M_DQ<5>
  VSS(45)  = GND
  DQ(1)  = M_M_DQ<1>
  VSS(44)  = GND
  DQS0N  = M_M_DQS_DN<0>
  DQS0P  = M_M_DQS_DP<0>
  VSS(43)  = GND
  DQ(7)  = M_M_DQ<7>
  VSS(42)  = GND
  DQ(3)  = M_M_DQ<3>
  VSS(41)  = GND
  DQ(13)  = M_M_DQ<13>
  VSS(40)  = GND
  DQ(9)  = M_M_DQ<9>
  VSS(39)  = GND
  DQS1N  = M_M_DQS_DN<1>
  DQS1P  = M_M_DQS_DP<1>
  VSS(38)  = GND
  DQ(15)  = M_M_DQ<15>
  VSS(37)  = GND
  DQ(11)  = M_M_DQ<11>
  VSS(36)  = GND
  DQ(21)  = M_M_DQ<21>
  VSS(35)  = GND
  DQ(17)  = M_M_DQ<17>
  VSS(34)  = GND
  DQS2N  = M_M_DQS_DN<2>
  DQS2P  = M_M_DQS_DP<2>
  VSS(33)  = GND
  DQ(23)  = M_M_DQ<23>
  VSS(32)  = GND
  DQ(19)  = M_M_DQ<19>
  VSS(31)  = GND
  DQ(29)  = M_M_DQ<29>
  VSS(30)  = GND
  DQ(25)  = M_M_DQ<25>
  VSS(29)  = GND
  DQS3N  = M_M_DQS_DN<3>
  DQS3P  = M_M_DQS_DP<3>
  VSS(28)  = GND
  DQ(31)  = M_M_DQ<31>
  VSS(27)  = GND
  DQ(27)  = M_M_DQ<27>
  VSS(26)  = GND
  CB(5)  = M_M_ECC<5>
  VSS(25)  = GND
  CB(1)  = M_M_ECC<1>
  VSS(24)  = GND
  DQS8N  = M_M_DQS_DN<8>
  DQS8P  = M_M_DQS_DP<8>
  VSS(23)  = GND
  CB(7)  = M_M_ECC<7>
  VSS(22)  = GND
  CB(3)  = M_M_ECC<3>
  VSS(21)  = GND
  CKE(1)  = M_M_CKE<3>
  VDD(12)  = PVDDQ_KLM
  RFU(0)  = TP_CH_M_DIMM_M1_RFU_0
  VDD(11)  = PVDDQ_KLM
  BG(1)  = M_M_BG<1>
  ALERT_N  = M_M_ALERT_N
  VDD(10)  = PVDDQ_KLM
  A11  = M_M_MA<11>
  A7  = M_M_MA<7>
  VDD(9)  = PVDDQ_KLM
  A5  = M_M_MA<5>
  A4  = M_M_MA<4>
  VDD(8)  = PVDDQ_KLM
  A2  = M_M_MA<2>
  VDD(7)  = PVDDQ_KLM
  CK1P  = M_M_CLK_DP<3>
  CK1N  = M_M_CLK_DN<3>
  VDD(6)  = PVDDQ_KLM
  VTT(0)  = PVTT_KLM
  PAR  = M_M_PAR
  VDD(5)  = PVDDQ_KLM
  BA(1)  = M_M_BA<1>
  A10  = M_M_MA<10>
  VDD(4)  = PVDDQ_KLM
  RFU(1)  = TP_CH_M_DIMM_M1_RFU_1
  A14_WE_N  = M_M_MA<14>
  VDD(3)  = PVDDQ_KLM
  SAVE_N_NC  = FM_ADR_COMPLETE_KLM_N
  VDD(2)  = PVDDQ_KLM
  A13  = M_M_MA<13>
  VDD(1)  = PVDDQ_KLM
  A17  = M_M_MA<17>
  C(2)  = M_M_C<2>
  VDD(0)  = PVDDQ_KLM
  S3_N_C(1)  = M_M_CS_N<7>
  SA(2)  = PVPP_KLM
  VSS(20)  = GND
  DQ(37)  = M_M_DQ<37>
  VSS(19)  = GND
  DQ(33)  = M_M_DQ<33>
  VSS(18)  = GND
  DQS4N  = M_M_DQS_DN<4>
  DQS4P  = M_M_DQS_DP<4>
  VSS(17)  = GND
  DQ(39)  = M_M_DQ<39>
  VSS(16)  = GND
  DQ(35)  = M_M_DQ<35>
  VSS(15)  = GND
  DQ(45)  = M_M_DQ<45>
  VSS(14)  = GND
  DQ(41)  = M_M_DQ<41>
  VSS(13)  = GND
  DQS5N  = M_M_DQS_DN<5>
  DQS5P  = M_M_DQS_DP<5>
  VSS(12)  = GND
  DQ(47)  = M_M_DQ<47>
  VSS(11)  = GND
  DQ(43)  = M_M_DQ<43>
  VSS(10)  = GND
  DQ(53)  = M_M_DQ<53>
  VSS(9)  = GND
  DQ(49)  = M_M_DQ<49>
  VSS(8)  = GND
  DQS6N  = M_M_DQS_DN<6>
  DQS6P  = M_M_DQS_DP<6>
  VSS(7)  = GND
  DQ(55)  = M_M_DQ<55>
  VSS(6)  = GND
  DQ(51)  = M_M_DQ<51>
  VSS(5)  = GND
  DQ(61)  = M_M_DQ<61>
  VSS(4)  = GND
  DQ(57)  = M_M_DQ<57>
  VSS(3)  = GND
  DQS7N  = M_M_DQS_DN<7>
  DQS7P  = M_M_DQS_DP<7>
  VSS(2)  = GND
  DQ(63)  = M_M_DQ<63>
  VSS(1)  = GND
  DQ(59)  = M_M_DQ<59>
  VSS(0)  = GND
  VDDSPD  = PVPP_KLM
  SDA  = SMB_DDR_KLM_VPP_SDA
  VPP(1)  = PVPP_KLM
  VPP(0)  = PVPP_KLM
  VPP(2)  = PVPP_KLM

(kicad_pcb
	(version 20260206)
	(generator "pcbnew")
	(generator_version "10.0")
	(general
		(thickness 1.6)
		(legacy_teardrops no)
	)
	(paper "A4")
	(title_block
		(title "Wiwynn_Tioga_Pass_MB.brd")
		(comment 1 "Tioga Pass / footprint 2717 of 4770 (J9L1), pads 152-201 of 291")
	)
	(layers
		(0 "F.Cu" signal "TOP")
		(4 "In1.Cu" signal "L2GND")
		(6 "In2.Cu" signal "L3")
		(8 "In3.Cu" signal "L4GND")
		(10 "In4.Cu" signal "L5")
		(12 "In5.Cu" signal "L6GND")
		(14 "In6.Cu" signal "L7VCC")
		(16 "In7.Cu" signal "L8VCC")
		(18 "In8.Cu" signal "L9GND")
		(20 "In9.Cu" signal "L10")
		(22 "In10.Cu" signal "L11GND")
		(24 "In11.Cu" signal "L12")
		(26 "In12.Cu" signal "L13GND")
		(2 "B.Cu" signal "BOTTOM")
		(9 "F.Adhes" user "F.Adhesive")
		(11 "B.Adhes" user "B.Adhesive")
		(13 "F.Paste" user "Package Geometry/Pastemask Top")
		(15 "B.Paste" user "Package Geometry/Pastemask Bottom")
		(5 "F.SilkS" user "Ref Des/Silkscreen Top")
		(7 "B.SilkS" user "Ref Des/Silkscreen Bottom")
		(1 "F.Mask" user "Board Geometry/Soldermask Top")
		(3 "B.Mask" user "Board Geometry/Soldermask Bottom")
		(17 "Dwgs.User" user "User.Drawings")
		(19 "Cmts.User" user "User.Comments")
		(21 "Eco1.User" user "User.Eco1")
		(23 "Eco2.User" user "User.Eco2")
		(25 "Edge.Cuts" user "Board Geometry/Outline")
		(27 "Margin" user)
		(31 "F.CrtYd" user "Package Geometry/Place Bound Top")
		(29 "B.CrtYd" user "Package Geometry/Place Bound Bottom")
		(35 "F.Fab" user "Ref Des/Assembly Top")
		(33 "B.Fab" user "Ref Des/Assembly Bottom")
	)
	(footprint ""
		(layer "B.Cu")
		(at 29.699458 -152.078436 90)
		(property "Reference" "J9L1"
			(at 2.200148 37.737542 0)
			(unlocked yes)
			(layer "B.SilkS")
			(effects
				(font
					(size 0.7874 0.5842)
					(thickness 0.1524)
				)
				(justify left mirror)
			)
		)
		(property "Value" ""
			(at 0 0 90)
			(layer "B.Fab")
			(effects
				(font
					(size 1.27 1.27)
				)
				(justify mirror)
			)
		)
		(duplicate_pad_numbers_are_jumpers no)
		(pad "149" smd rect
			(at -4.59994 3.400044 270)
			(size 1.8034 0.508)
			(layers "B.Cu" "B.Mask" "B.Paste")
			(net "GND")
		)
		(pad "150" smd rect
			(at -4.59994 4.249928 270)
			(size 1.8034 0.508)
			(layers "B.Cu" "B.Mask" "B.Paste")
			(net "M_M_DQ<1>")
		)
		(pad "151" smd rect
			(at -4.59994 5.100066 270)
			(size 1.8034 0.508)
			(layers "B.Cu" "B.Mask" "B.Paste")
			(net "GND")
		)
		(pad "152" smd rect
			(at -4.59994 5.94995 270)
			(size 1.8034 0.508)
			(layers "B.Cu" "B.Mask" "B.Paste")
			(net "M_M_DQS_DN<0>")
		)
		(pad "153" smd rect
			(at -4.59994 6.800088 270)
			(size 1.8034 0.508)
			(layers "B.Cu" "B.Mask" "B.Paste")
			(net "M_M_DQS_DP<0>")
		)
		(pad "154" smd rect
			(at -4.59994 7.649972 270)
			(size 1.8034 0.508)
			(layers "B.Cu" "B.Mask" "B.Paste")
			(net "GND")
		)
		(pad "155" smd rect
			(at -4.59994 8.50011 270)
			(size 1.8034 0.508)
			(layers "B.Cu" "B.Mask" "B.Paste")
			(net "M_M_DQ<7>")
		)
		(pad "156" smd rect
			(at -4.59994 9.349994 270)
			(size 1.8034 0.508)
			(layers "B.Cu" "B.Mask" "B.Paste")
			(net "GND")
		)
		(pad "157" smd rect
			(at -4.59994 10.199878 270)
			(size 1.8034 0.508)
			(layers "B.Cu" "B.Mask" "B.Paste")
			(net "M_M_DQ<3>")
		)
		(pad "158" smd rect
			(at -4.59994 11.050016 270)
			(size 1.8034 0.508)
			(layers "B.Cu" "B.Mask" "B.Paste")
			(net "GND")
		)
		(pad "159" smd rect
			(at -4.59994 11.8999 270)
			(size 1.8034 0.508)
			(layers "B.Cu" "B.Mask" "B.Paste")
			(net "M_M_DQ<13>")
		)
		(pad "160" smd rect
			(at -4.59994 12.750038 270)
			(size 1.8034 0.508)
			(layers "B.Cu" "B.Mask" "B.Paste")
			(net "GND")
		)
		(pad "161" smd rect
			(at -4.59994 13.599922 270)
			(size 1.8034 0.508)
			(layers "B.Cu" "B.Mask" "B.Paste")
			(net "M_M_DQ<9>")
		)
		(pad "162" smd rect
			(at -4.59994 14.45006 270)
			(size 1.8034 0.508)
			(layers "B.Cu" "B.Mask" "B.Paste")
			(net "GND")
		)
		(pad "163" smd rect
			(at -4.59994 15.299944 270)
			(size 1.8034 0.508)
			(layers "B.Cu" "B.Mask" "B.Paste")
			(net "M_M_DQS_DN<1>")
		)
		(pad "164" smd rect
			(at -4.59994 16.150082 270)
			(size 1.8034 0.508)
			(layers "B.Cu" "B.Mask" "B.Paste")
			(net "M_M_DQS_DP<1>")
		)
		(pad "165" smd rect
			(at -4.59994 16.999966 270)
			(size 1.8034 0.508)
			(layers "B.Cu" "B.Mask" "B.Paste")
			(net "GND")
		)
		(pad "166" smd rect
			(at -4.59994 17.850104 270)
			(size 1.8034 0.508)
			(layers "B.Cu" "B.Mask" "B.Paste")
			(net "M_M_DQ<15>")
		)
		(pad "167" smd rect
			(at -4.59994 18.699988 270)
			(size 1.8034 0.508)
			(layers "B.Cu" "B.Mask" "B.Paste")
			(net "GND")
		)
		(pad "168" smd rect
			(at -4.59994 19.550126 270)
			(size 1.8034 0.508)
			(layers "B.Cu" "B.Mask" "B.Paste")
			(net "M_M_DQ<11>")
		)
		(pad "169" smd rect
			(at -4.59994 20.40001 270)
			(size 1.8034 0.508)
			(layers "B.Cu" "B.Mask" "B.Paste")
			(net "GND")
		)
		(pad "170" smd rect
			(at -4.59994 21.249894 270)
			(size 1.8034 0.508)
			(layers "B.Cu" "B.Mask" "B.Paste")
			(net "M_M_DQ<21>")
		)
		(pad "171" smd rect
			(at -4.59994 22.100032 270)
			(size 1.8034 0.508)
			(layers "B.Cu" "B.Mask" "B.Paste")
			(net "GND")
		)
		(pad "172" smd rect
			(at -4.59994 22.949916 270)
			(size 1.8034 0.508)
			(layers "B.Cu" "B.Mask" "B.Paste")
			(net "M_M_DQ<17>")
		)
		(pad "173" smd rect
			(at -4.59994 23.800054 270)
			(size 1.8034 0.508)
			(layers "B.Cu" "B.Mask" "B.Paste")
			(net "GND")
		)
		(pad "174" smd rect
			(at -4.59994 24.649938 270)
			(size 1.8034 0.508)
			(layers "B.Cu" "B.Mask" "B.Paste")
			(net "M_M_DQS_DN<2>")
		)
		(pad "175" smd rect
			(at -4.59994 25.500076 270)
			(size 1.8034 0.508)
			(layers "B.Cu" "B.Mask" "B.Paste")
			(net "M_M_DQS_DP<2>")
		)
		(pad "176" smd rect
			(at -4.59994 26.34996 270)
			(size 1.8034 0.508)
			(layers "B.Cu" "B.Mask" "B.Paste")
			(net "GND")
		)
		(pad "177" smd rect
			(at -4.59994 27.200098 270)
			(size 1.8034 0.508)
			(layers "B.Cu" "B.Mask" "B.Paste")
			(net "M_M_DQ<23>")
		)
		(pad "178" smd rect
			(at -4.59994 28.049982 270)
			(size 1.8034 0.508)
			(layers "B.Cu" "B.Mask" "B.Paste")
			(net "GND")
		)
		(pad "179" smd rect
			(at -4.59994 28.90012 270)
			(size 1.8034 0.508)
			(layers "B.Cu" "B.Mask" "B.Paste")
			(net "M_M_DQ<19>")
		)
		(pad "180" smd rect
			(at -4.59994 29.750004 270)
			(size 1.8034 0.508)
			(layers "B.Cu" "B.Mask" "B.Paste")
			(net "GND")
		)
		(pad "181" smd rect
			(at -4.59994 30.599888 270)
			(size 1.8034 0.508)
			(layers "B.Cu" "B.Mask" "B.Paste")
			(net "M_M_DQ<29>")
		)
		(pad "182" smd rect
			(at -4.59994 31.450026 270)
			(size 1.8034 0.508)
			(layers "B.Cu" "B.Mask" "B.Paste")
			(net "GND")
		)
		(pad "183" smd rect
			(at -4.59994 32.29991 270)
			(size 1.8034 0.508)
			(layers "B.Cu" "B.Mask" "B.Paste")
			(net "M_M_DQ<25>")
		)
		(pad "184" smd rect
			(at -4.59994 33.150048 270)
			(size 1.8034 0.508)
			(layers "B.Cu" "B.Mask" "B.Paste")
			(net "GND")
		)
		(pad "185" smd rect
			(at -4.59994 33.999932 270)
			(size 1.8034 0.508)
			(layers "B.Cu" "B.Mask" "B.Paste")
			(net "M_M_DQS_DN<3>")
		)
		(pad "186" smd rect
			(at -4.59994 34.85007 270)
			(size 1.8034 0.508)
			(layers "B.Cu" "B.Mask" "B.Paste")
			(net "M_M_DQS_DP<3>")
		)
		(pad "187" smd rect
			(at -4.59994 35.699954 270)
			(size 1.8034 0.508)
			(layers "B.Cu" "B.Mask" "B.Paste")
			(net "GND")
		)
		(pad "188" smd rect
			(at -4.59994 36.550092 270)
			(size 1.8034 0.508)
			(layers "B.Cu" "B.Mask" "B.Paste")
			(net "M_M_DQ<31>")
		)
		(pad "189" smd rect
			(at -4.59994 37.399976 270)
			(size 1.8034 0.508)
			(layers "B.Cu" "B.Mask" "B.Paste")
			(net "GND")
		)
		(pad "190" smd rect
			(at -4.59994 38.250114 270)
			(size 1.8034 0.508)
			(layers "B.Cu" "B.Mask" "B.Paste")
			(net "M_M_DQ<27>")
		)
		(pad "191" smd rect
			(at -4.59994 39.099998 270)
			(size 1.8034 0.508)
			(layers "B.Cu" "B.Mask" "B.Paste")
			(net "GND")
		)
		(pad "192" smd rect
			(at -4.59994 39.949882 270)
			(size 1.8034 0.508)
			(layers "B.Cu" "B.Mask" "B.Paste")
			(net "M_M_ECC<5>")
		)
		(pad "193" smd rect
			(at -4.59994 40.80002 270)
			(size 1.8034 0.508)
			(layers "B.Cu" "B.Mask" "B.Paste")
			(net "GND")
		)
		(pad "194" smd rect
			(at -4.59994 41.649904 270)
			(size 1.8034 0.508)
			(layers "B.Cu" "B.Mask" "B.Paste")
			(net "M_M_ECC<1>")
		)
		(pad "195" smd rect
			(at -4.59994 42.500042 270)
			(size 1.8034 0.508)
			(layers "B.Cu" "B.Mask" "B.Paste")
			(net "GND")
		)
		(pad "196" smd rect
			(at -4.59994 43.349926 270)
			(size 1.8034 0.508)
			(layers "B.Cu" "B.Mask" "B.Paste")
			(net "M_M_DQS_DN<8>")
		)
		(pad "197" smd rect
			(at -4.59994 44.200064 270)
			(size 1.8034 0.508)
			(layers "B.Cu" "B.Mask" "B.Paste")
			(net "M_M_DQS_DP<8>")
		)
		(pad "198" smd rect
			(at -4.59994 45.049948 270)
			(size 1.8034 0.508)
			(layers "B.Cu" "B.Mask" "B.Paste")
			(net "GND")
		)
	)
)
